# S9S_MB_2U (Grand Teton) — schematic netlist excerpt (pin names and nets, part order shuffled) for the footprints in the layout excerpt that follows; sources: Cadence DE-HDL packaged netlist, KiCad conversion of 03242023_DA0F0TMBIJ0_F0T_Motherboard_J_brd_V01_OCP.brd

C1882  Q_CAP  0.1UF 25V 10% X7R  pkg 0402  page 212 : A = P3V3_AUX ; B = GND
PC271  Q_CAP  2.2UF 10V 10% X6S  pkg C0402  page 268 : A = PVCCIN_CPU0_VDD3 ; B = GND

(kicad_pcb
	(version 20260206)
	(generator "pcbnew")
	(generator_version "10.0")
	(general
		(thickness 1.6)
		(legacy_teardrops no)
	)
	(paper "A4")
	(title_block
		(title "03242023_DA0F0TMBIJ0_F0T_Motherboard_J_brd_V01_OCP.brd")
		(comment 1 "Grand Teton / footprints 470-471 of 6105")
	)
	(layers
		(0 "F.Cu" signal "TOP")
		(4 "In1.Cu" signal "GND")
		(6 "In2.Cu" signal "IN1")
		(8 "In3.Cu" signal "GND1")
		(10 "In4.Cu" signal "IN2")
		(12 "In5.Cu" signal "GND2")
		(14 "In6.Cu" signal "IN3")
		(16 "In7.Cu" signal "GND3")
		(18 "In8.Cu" signal "VCC")
		(20 "In9.Cu" signal "VCC1")
		(22 "In10.Cu" signal "GND4")
		(24 "In11.Cu" signal "IN4")
		(26 "In12.Cu" signal "GND5")
		(28 "In13.Cu" signal "IN5")
		(30 "In14.Cu" signal "GND6")
		(32 "In15.Cu" signal "IN6")
		(34 "In16.Cu" signal "GND7")
		(2 "B.Cu" signal "BOTTOM")
		(9 "F.Adhes" user "F.Adhesive")
		(11 "B.Adhes" user "B.Adhesive")
		(13 "F.Paste" user "Package Geometry/Pastemask Top")
		(15 "B.Paste" user "Package Geometry/Pastemask Bottom")
		(5 "F.SilkS" user "Ref Des/Silkscreen Top")
		(7 "B.SilkS" user "Ref Des/Silkscreen Bottom")
		(1 "F.Mask" user "Board Geometry/Soldermask Top")
		(3 "B.Mask" user "Board Geometry/Soldermask Bottom")
		(17 "Dwgs.User" user "User.Drawings")
		(19 "Cmts.User" user "User.Comments")
		(21 "Eco1.User" user "User.Eco1")
		(23 "Eco2.User" user "User.Eco2")
		(25 "Edge.Cuts" user "Board Geometry/Outline")
		(27 "Margin" user)
		(31 "F.CrtYd" user "Package Geometry/Place Bound Top")
		(29 "B.CrtYd" user "Package Geometry/Place Bound Bottom")
		(35 "F.Fab" user "Ref Des/Assembly Top")
		(33 "B.Fab" user "Ref Des/Assembly Bottom")
	)
	(footprint ""
		(layer "F.Cu")
		(at 357.683816 -336.192368 90)
		(property "Reference" "PC271"
			(at 0 0 90)
			(layer "F.SilkS")
			(hide yes)
			(effects
				(font
					(size 1.27 1.27)
				)
			)
		)
		(property "Value" ""
			(at 0 0 90)
			(layer "F.Fab")
			(effects
				(font
					(size 1.27 1.27)
				)
			)
		)
		(duplicate_pad_numbers_are_jumpers no)
		(fp_line
			(start 0.7874 -0.4064)
			(end 0.7874 0.4064)
			(stroke
				(width 0.1524)
				(type default)
			)
			(layer "F.SilkS")
		)
		(fp_line
			(start -0.7874 -0.4064)
			(end 0.7874 -0.4064)
			(stroke
				(width 0.1524)
				(type default)
			)
			(layer "F.SilkS")
		)
		(fp_line
			(start 0.7874 0.4064)
			(end -0.7874 0.4064)
			(stroke
				(width 0.1524)
				(type default)
			)
			(layer "F.SilkS")
		)
		(fp_line
			(start -0.7874 0.4064)
			(end -0.7874 -0.4064)
			(stroke
				(width 0.1524)
				(type default)
			)
			(layer "F.SilkS")
		)
		(fp_line
			(start -0.12065 -0.305054)
			(end -0.12065 -0.2794)
			(stroke
				(width 0.1)
				(type default)
			)
			(layer "F.Fab")
		)
		(fp_line
			(start -0.67945 -0.305054)
			(end -0.12065 -0.305054)
			(stroke
				(width 0.1)
				(type default)
			)
			(layer "F.Fab")
		)
		(fp_line
			(start 0.67945 -0.3048)
			(end 0.67945 0.3048)
			(stroke
				(width 0.1)
				(type default)
			)
			(layer "F.Fab")
		)
		(fp_line
			(start 0.12065 -0.3048)
			(end 0.67945 -0.3048)
			(stroke
				(width 0.1)
				(type default)
			)
			(layer "F.Fab")
		)
		(fp_line
			(start 0.12065 -0.2794)
			(end 0.12065 -0.3048)
			(stroke
				(width 0.1)
				(type default)
			)
			(layer "F.Fab")
		)
		(fp_line
			(start -0.12065 -0.2794)
			(end 0.12065 -0.2794)
			(stroke
				(width 0.1)
				(type default)
			)
			(layer "F.Fab")
		)
		(fp_line
			(start 0.120396 0.2794)
			(end -0.12065 0.2794)
			(stroke
				(width 0.1)
				(type default)
			)
			(layer "F.Fab")
		)
		(fp_line
			(start -0.12065 0.2794)
			(end -0.12065 0.3048)
			(stroke
				(width 0.1)
				(type default)
			)
			(layer "F.Fab")
		)
		(fp_line
			(start 0.67945 0.3048)
			(end 0.120396 0.3048)
			(stroke
				(width 0.1)
				(type default)
			)
			(layer "F.Fab")
		)
		(fp_line
			(start 0.120396 0.3048)
			(end 0.120396 0.2794)
			(stroke
				(width 0.1)
				(type default)
			)
			(layer "F.Fab")
		)
		(fp_line
			(start -0.12065 0.3048)
			(end -0.67945 0.3048)
			(stroke
				(width 0.1)
				(type default)
			)
			(layer "F.Fab")
		)
		(fp_line
			(start -0.67945 0.3048)
			(end -0.67945 -0.305054)
			(stroke
				(width 0.1)
				(type default)
			)
			(layer "F.Fab")
		)
		(pad "1" smd circle
			(at -0.40005 0 90)
			(size 0 0)
			(layers "F.Cu" "F.Mask" "F.Paste")
			(net "PVCCIN_CPU0_VDD3")
		)
		(pad "2" smd circle
			(at 0.40005 0 90)
			(size 0 0)
			(layers "F.Cu" "F.Mask" "F.Paste")
			(net "GND")
		)
	)
	(footprint ""
		(layer "F.Cu")
		(at 122.636534 -40.351456)
		(property "Reference" "C1882"
			(at 0 0 0)
			(layer "F.SilkS")
			(hide yes)
			(effects
				(font
					(size 1.27 1.27)
				)
			)
		)
		(property "Value" ""
			(at 0 0 0)
			(layer "F.Fab")
			(effects
				(font
					(size 1.27 1.27)
				)
			)
		)
		(duplicate_pad_numbers_are_jumpers no)
		(fp_line
			(start -0.7874 -0.4064)
			(end 0.7874 -0.4064)
			(stroke
				(width 0.1524)
				(type default)
			)
			(layer "F.SilkS")
		)
		(fp_line
			(start -0.7874 0.4064)
			(end -0.7874 -0.4064)
			(stroke
				(width 0.1524)
				(type default)
			)
			(layer "F.SilkS")
		)
		(fp_line
			(start 0.7874 -0.4064)
			(end 0.7874 0.4064)
			(stroke
				(width 0.1524)
				(type default)
			)
			(layer "F.SilkS")
		)
		(fp_line
			(start 0.7874 0.4064)
			(end -0.7874 0.4064)
			(stroke
				(width 0.1524)
				(type default)
			)
			(layer "F.SilkS")
		)
		(fp_line
			(start -0.67945 -0.305054)
			(end -0.12065 -0.305054)
			(stroke
				(width 0.1)
				(type default)
			)
			(layer "F.Fab")
		)
		(fp_line
			(start -0.67945 0.3048)
			(end -0.67945 -0.305054)
			(stroke
				(width 0.1)
				(type default)
			)
			(layer "F.Fab")
		)
		(fp_line
			(start -0.12065 -0.305054)
			(end -0.12065 -0.2794)
			(stroke
				(width 0.1)
				(type default)
			)
			(layer "F.Fab")
		)
		(fp_line
			(start -0.12065 -0.2794)
			(end 0.12065 -0.2794)
			(stroke
				(width 0.1)
				(type default)
			)
			(layer "F.Fab")
		)
		(fp_line
			(start -0.12065 0.2794)
			(end -0.12065 0.3048)
			(stroke
				(width 0.1)
				(type default)
			)
			(layer "F.Fab")
		)
		(fp_line
			(start -0.12065 0.3048)
			(end -0.67945 0.3048)
			(stroke
				(width 0.1)
				(type default)
			)
			(layer "F.Fab")
		)
		(fp_line
			(start 0.120396 0.2794)
			(end -0.12065 0.2794)
			(stroke
				(width 0.1)
				(type default)
			)
			(layer "F.Fab")
		)
		(fp_line
			(start 0.120396 0.3048)
			(end 0.120396 0.2794)
			(stroke
				(width 0.1)
				(type default)
			)
			(layer "F.Fab")
		)
		(fp_line
			(start 0.12065 -0.3048)
			(end 0.67945 -0.3048)
			(stroke
				(width 0.1)
				(type default)
			)
			(layer "F.Fab")
		)
		(fp_line
			(start 0.12065 -0.2794)
			(end 0.12065 -0.3048)
			(stroke
				(width 0.1)
				(type default)
			)
			(layer "F.Fab")
		)
		(fp_line
			(start 0.67945 -0.3048)
			(end 0.67945 0.3048)
			(stroke
				(width 0.1)
				(type default)
			)
			(layer "F.Fab")
		)
		(fp_line
			(start 0.67945 0.3048)
			(end 0.120396 0.3048)
			(stroke
				(width 0.1)
				(type default)
			)
			(layer "F.Fab")
		)
		(pad "1" smd circle
			(at -0.40005 0)
			(size 0 0)
			(layers "F.Cu" "F.Mask" "F.Paste")
			(net "P3V3_AUX")
		)
		(pad "2" smd circle
			(at 0.40005 0)
			(size 0 0)
			(layers "F.Cu" "F.Mask" "F.Paste")
			(net "GND")
		)
	)
)
